G04 ================== begin FILE IDENTIFICATION RECORD ==================*
G04 Layout Name:  13919-sa.brd*
G04 Film Name:    L1*
G04 File Format:  Gerber RS274X*
G04 File Origin:  Cadence Allegro 16.5-S039*
G04 Origin Date:  Fri Nov 22 15:27:04 2013*
G04 *
G04 Layer:  VIA CLASS/TOP*
G04 Layer:  PIN/TOP*
G04 Layer:  ETCH/TOP*
G04 Layer:  DRAWING FORMAT/LAYER_L1*
G04 Layer:  DRAWING FORMAT/LAYER_PCB_STORY*
G04 *
G04 Offset:    (0.00 0.00)*
G04 Mirror:    No*
G04 Mode:      Positive*
G04 Rotation:  0*
G04 FullContactRelief:  No*
G04 UndefLineWidth:     6.00*
G04 ================== end FILE IDENTIFICATION RECORD ====================*
%FSLAX35Y35*MOIN*%
%IR0*IPPOS*OFA0.00000B0.00000*MIA0B0*SFA1.00000B1.00000*%
%ADD13C,.01*%
%ADD11C,.022*%
%ADD15R,.028X.126*%
%ADD14C,.043*%
%ADD10R,.028X.165*%
%ADD12C,.028*%
%ADD16C,.02*%
%ADD17C,.025*%
%ADD18C,.005*%
%ADD19C,.006*%
%ADD20C,.0055*%
%ADD21C,.00425*%
%ADD22C,.06704*%
G75*
%LPD*%
G75*
G36*
G01X31633Y80900D02*
X35120Y77413D01*
G02X34901Y76735I-283J-283D01*
G03X35567Y70077I532J-3309D01*
G02X35983Y69677I16J-400D01*
G01Y42220D01*
X33293Y39530D01*
Y39013D01*
X33274Y38927D01*
X33266Y38908D01*
G03X33293Y36953I2097J-949D01*
G01Y31450D01*
X33288Y31445D01*
Y29768D01*
X33232Y29712D01*
Y29274D01*
X28278Y24320D01*
X25093D01*
X23583Y25830D01*
Y33150D01*
X22754Y33979D01*
X22744Y33992D01*
X22742Y33994D01*
G03X21185Y35548I-5618J-4071D01*
G01X11321Y45412D01*
G02X11411Y46045I283J283D01*
G03X10181Y56172I-2661J4815D01*
G01X10033Y56212D01*
Y67100D01*
X12333Y69400D01*
Y73386D01*
G02X12976Y73703I400J0D01*
G03X22031Y80362I3562J4643D01*
G02X22406Y80900I376J138D01*
G01X25184D01*
G03X29932I2374J2366D01*
G01X31633D01*
G37*
G36*
G01X341333Y24000D02*
X340784Y24548D01*
Y31377D01*
X340793Y31404D01*
G03X339152Y34281I-2210J646D01*
G01X339099Y34294D01*
X334504Y38888D01*
Y62734D01*
X335135Y63364D01*
G02X335859Y63597I400J-1D01*
G03Y67505I2724J1954D01*
G02X335134Y67738I-325J233D01*
G01Y70105D01*
X335296Y70137D01*
G03X336833Y75968I-648J3289D01*
G01Y80724D01*
G03Y85808I-2185J2542D01*
G01Y87640D01*
G02X337377Y88014I400J1D01*
G03X338312Y94482I1206J3127D01*
G02X337996Y95163I-33J399D01*
G01X338633Y95800D01*
X359179D01*
X359216Y95646D01*
G03X367107Y92028I5354J1264D01*
G01X367237Y92096D01*
X368433Y90900D01*
Y68690D01*
X366753Y67010D01*
X353950D01*
X352490Y65550D01*
G02X351807Y65833I-283J283D01*
G01Y70387D01*
G03X348978I-1415J3039D01*
G01Y68646D01*
G02X348352Y68316I-400J0D01*
G03X346795Y62216I-1894J-2765D01*
G02X347236Y61818I41J-398D01*
G01Y36384D01*
X348982Y34638D01*
Y30582D01*
X348980Y30580D01*
Y24846D01*
X348133Y24000D01*
X341333D01*
G37*
%LPC*%
G75*
G54D22*
X31498Y65551D03*
X27558Y73426D03*
X23623Y65551D03*
X342518Y73426D03*
X350393Y83266D03*
X346458Y91141D03*
X342518Y83266D03*
%LPD*%
G75*
G54D10*
X23622Y13762D03*
X27559D03*
X31496D03*
X35433D03*
X39370D03*
X43307D03*
X47244D03*
X51181D03*
X55118D03*
X59055D03*
X62992D03*
X66929D03*
X70866D03*
X74803D03*
X78740D03*
X82677D03*
X86614D03*
X90551D03*
X94488D03*
X98425D03*
X102362D03*
X106299D03*
X110236D03*
X114173D03*
X118110D03*
X122047D03*
X125984D03*
X129921D03*
X133858D03*
X137795D03*
X141732D03*
X145669D03*
X149606D03*
X153543D03*
X157480D03*
X161417D03*
X165354D03*
X169291D03*
X173228D03*
X177165D03*
X181102D03*
X185039D03*
X188976D03*
X192913D03*
X196850D03*
X200787D03*
X204724D03*
X208661D03*
X212598D03*
X216535D03*
X220472D03*
X224409D03*
X228346D03*
X232283D03*
X236220D03*
X240157D03*
X244094D03*
X248031D03*
X251968D03*
X255905D03*
X259842D03*
X263779D03*
X267716D03*
X271653D03*
X275590D03*
X279527D03*
X283464D03*
X287401D03*
X291338D03*
X295275D03*
X299212D03*
X311024D03*
X314961D03*
X318898D03*
X322835D03*
X326772D03*
X330709D03*
X334646D03*
X338583D03*
X342520D03*
X346457D03*
G54D20*
G01X43308Y73426D02*
X43150Y73268D01*
Y69268D01*
X44118Y68300D01*
Y59095D01*
X42033Y57010D01*
Y23901D01*
X43307Y22627D01*
Y13762D01*
G01X39373Y65551D02*
X39372D01*
Y67454D01*
X40558Y68640D01*
X41868D01*
X42768Y67740D01*
Y59655D01*
X40683Y57570D01*
Y23939D01*
X39370Y22626D01*
Y13762D01*
G01X59058Y73426D02*
X59057D01*
Y69106D01*
X59863Y68300D01*
Y59263D01*
X57762Y57162D01*
Y51890D01*
X57767Y51885D01*
Y51640D01*
X57762Y51635D01*
Y23920D01*
X59055Y22627D01*
Y13762D01*
G01X55118Y65551D02*
X55117D01*
Y67454D01*
X56243Y68580D01*
X57673D01*
X58513Y67740D01*
Y59823D01*
X56412Y57722D01*
Y23920D01*
X55118Y22626D01*
Y13762D01*
G01X74803Y73426D02*
X74600Y73223D01*
Y69308D01*
X75608Y68300D01*
Y59095D01*
X73510Y56997D01*
Y23920D01*
X74803Y22627D01*
Y13762D01*
G01X70868Y65551D02*
X70867D01*
Y67459D01*
X72018Y68610D01*
X73388D01*
X74258Y67740D01*
Y59655D01*
X72160Y57557D01*
Y23920D01*
X70866Y22626D01*
Y13762D01*
G01X90553Y73426D02*
X90410Y73283D01*
Y69243D01*
X91353Y68300D01*
Y59095D01*
X89258Y57000D01*
Y23920D01*
X90551Y22627D01*
Y13762D01*
G01X86613Y65551D02*
X86612D01*
Y67459D01*
X87793Y68640D01*
X89103D01*
X90003Y67740D01*
Y59655D01*
X87907Y57559D01*
X87908Y57558D01*
Y23920D01*
X86614Y22626D01*
Y13762D01*
G01X106298Y73426D02*
X106297D01*
X106302Y73421D01*
Y69101D01*
X107103Y68300D01*
Y59095D01*
X103120Y55112D01*
Y54008D01*
X103670Y53458D01*
X105552D01*
X106892Y52118D01*
Y49898D01*
X105552Y48558D01*
X103670D01*
X103120Y48008D01*
Y46908D01*
X103670Y46358D01*
X105552D01*
X106892Y45018D01*
Y42798D01*
X105552Y41458D01*
X103670D01*
X103120Y40908D01*
Y39808D01*
X105006Y37922D01*
Y23920D01*
X106299Y22627D01*
Y13762D01*
G01X102363Y65551D02*
X102362D01*
Y67459D01*
X103403Y68500D01*
X104993D01*
X105753Y67740D01*
Y59655D01*
X101770Y55672D01*
Y53448D01*
X103110Y52108D01*
X104992D01*
X105542Y51558D01*
Y50458D01*
X104992Y49908D01*
X103110D01*
X101770Y48568D01*
Y46348D01*
X103110Y45008D01*
X104992D01*
X105542Y44458D01*
Y43358D01*
X104992Y42808D01*
X103110D01*
X101770Y41468D01*
Y39248D01*
X103656Y37362D01*
Y23920D01*
X102362Y22626D01*
Y13762D01*
G01X122048Y73426D02*
X122047D01*
X122052Y73421D01*
Y69101D01*
X122853Y68300D01*
Y59095D01*
X118880Y55122D01*
Y54006D01*
X119430Y53456D01*
X121288D01*
X122628Y52116D01*
Y49896D01*
X121288Y48556D01*
X119430D01*
X118880Y48006D01*
Y46906D01*
X119430Y46356D01*
X121288D01*
X122628Y45016D01*
Y42796D01*
X121288Y41456D01*
X119430D01*
X118880Y40906D01*
Y39806D01*
X120754Y37932D01*
Y23920D01*
X122047Y22627D01*
Y13762D01*
G01X118113Y65551D02*
X118112D01*
Y67459D01*
X119153Y68500D01*
X120743D01*
X121503Y67740D01*
Y59655D01*
X117530Y55682D01*
Y53446D01*
X118870Y52106D01*
X120728D01*
X121278Y51556D01*
Y50456D01*
X120728Y49906D01*
X118870D01*
X117530Y48566D01*
Y46346D01*
X118870Y45006D01*
X120728D01*
X121278Y44456D01*
Y43356D01*
X120728Y42806D01*
X118870D01*
X117530Y41466D01*
Y39246D01*
X119404Y37372D01*
Y23920D01*
X118110Y22626D01*
Y13762D01*
G01X137798Y73426D02*
X137797D01*
Y69101D01*
X138598Y68300D01*
Y59095D01*
X134640Y55137D01*
Y54009D01*
X135190Y53459D01*
X137024D01*
X138364Y52119D01*
Y49899D01*
X137024Y48559D01*
X135190D01*
X134640Y48009D01*
Y46909D01*
X135190Y46359D01*
X137024D01*
X138364Y45019D01*
Y42799D01*
X137024Y41459D01*
X135190D01*
X134640Y40909D01*
Y39809D01*
X136502Y37947D01*
Y23920D01*
X137795Y22627D01*
Y13762D01*
G01X133858Y65551D02*
X133857D01*
Y67459D01*
X134898Y68500D01*
X136488D01*
X137248Y67740D01*
Y59655D01*
X133290Y55697D01*
Y53449D01*
X134630Y52109D01*
X136464D01*
X137014Y51559D01*
Y50459D01*
X136464Y49909D01*
X134630D01*
X133290Y48569D01*
Y46349D01*
X134630Y45009D01*
X136464D01*
X137014Y44459D01*
Y43359D01*
X136464Y42809D01*
X134630D01*
X133290Y41469D01*
Y39249D01*
X135152Y37387D01*
Y23920D01*
X133858Y22626D01*
Y13762D01*
G01X153543Y73426D02*
X153542D01*
X153547Y73421D01*
Y69101D01*
X154348Y68300D01*
Y59095D01*
X150400Y55147D01*
Y54007D01*
X150950Y53457D01*
X152760D01*
X154100Y52117D01*
Y49897D01*
X152760Y48557D01*
X150950D01*
X150400Y48007D01*
Y46907D01*
X150950Y46357D01*
X152850D01*
X154140Y45067D01*
Y42747D01*
X152850Y41457D01*
X150950D01*
X150400Y40907D01*
Y39807D01*
X152250Y37957D01*
Y23920D01*
X153543Y22627D01*
Y13762D01*
G01X149608Y65551D02*
X149607D01*
Y67459D01*
X150648Y68500D01*
X152238D01*
X152998Y67740D01*
Y59655D01*
X149050Y55707D01*
Y53447D01*
X150390Y52107D01*
X152200D01*
X152750Y51557D01*
Y50457D01*
X152200Y49907D01*
X150390D01*
X149050Y48567D01*
Y46347D01*
X150390Y45007D01*
X152290D01*
X152790Y44507D01*
Y43307D01*
X152290Y42807D01*
X150390D01*
X149050Y41467D01*
Y39247D01*
X150900Y37397D01*
Y23920D01*
X149606Y22626D01*
Y13762D01*
G01X165353Y65551D02*
X165352D01*
Y67459D01*
X166393Y68500D01*
X167983D01*
X168743Y67740D01*
Y59655D01*
X166647Y57559D01*
X166648Y57558D01*
Y23920D01*
X165354Y22626D01*
Y13762D01*
G01X169293Y73426D02*
X169292D01*
Y69101D01*
X170093Y68300D01*
Y59095D01*
X167998Y57000D01*
Y23920D01*
X169291Y22627D01*
Y13762D01*
G01X216538Y73426D02*
X216537D01*
Y69101D01*
X217338Y68300D01*
Y63288D01*
X215243Y61193D01*
Y23919D01*
X216535Y22627D01*
Y13762D01*
G01X212598Y65551D02*
X212597D01*
Y67414D01*
X213743Y68560D01*
X215168D01*
X215988Y67740D01*
Y63848D01*
X213893Y61753D01*
Y23921D01*
X212598Y22626D01*
Y13762D01*
G01X228348Y65551D02*
X228347D01*
Y67459D01*
X229388Y68500D01*
X230978D01*
X231738Y67740D01*
Y63128D01*
X228000Y59390D01*
Y56920D01*
X229340Y55580D01*
X230730D01*
X231280Y55030D01*
Y53930D01*
X230730Y53380D01*
X229340D01*
X228000Y52040D01*
Y49820D01*
X229340Y48480D01*
X230730D01*
X231280Y47930D01*
Y46830D01*
X230730Y46280D01*
X229340D01*
X228000Y44940D01*
Y42720D01*
X229340Y41380D01*
X230730D01*
X231280Y40830D01*
Y39730D01*
X229640Y38090D01*
Y23920D01*
X228346Y22626D01*
Y13762D01*
G01X232283Y73426D02*
X232282D01*
Y69106D01*
X233088Y68300D01*
Y62568D01*
X229350Y58830D01*
Y57480D01*
X229900Y56930D01*
X231290D01*
X232630Y55590D01*
Y53370D01*
X231290Y52030D01*
X229900D01*
X229350Y51480D01*
Y50380D01*
X229900Y49830D01*
X231290D01*
X232630Y48490D01*
Y46270D01*
X231290Y44930D01*
X229900D01*
X229350Y44380D01*
Y43280D01*
X229900Y42730D01*
X231290D01*
X232630Y41390D01*
Y39170D01*
X230990Y37530D01*
Y23920D01*
X232283Y22627D01*
Y13762D01*
G01X291338Y65551D02*
X291337D01*
X294286Y68500D01*
X301403D01*
X302233Y67670D01*
Y40010D01*
X300503Y38280D01*
X294273D01*
X290783Y34790D01*
Y28850D01*
X292632Y27001D01*
Y23920D01*
X291338Y22626D01*
Y13762D01*
G01X248033Y73426D02*
X248032D01*
Y69101D01*
X248790Y68343D01*
Y61195D01*
X244450Y56855D01*
Y55755D01*
X245000Y55205D01*
X247686D01*
X249026Y53865D01*
Y51645D01*
X247686Y50305D01*
X245090D01*
X244590Y49805D01*
Y48605D01*
X245090Y48105D01*
X247686D01*
X249026Y46765D01*
Y44545D01*
X246738Y42257D01*
Y23920D01*
X248031Y22627D01*
Y13762D01*
G01X244093Y65551D02*
X244092D01*
Y67459D01*
X245133Y68500D01*
X246723D01*
X247440Y67783D01*
Y61755D01*
X243100Y57415D01*
Y55195D01*
X244440Y53855D01*
X247126D01*
X247676Y53305D01*
Y52205D01*
X247126Y51655D01*
X244530D01*
X243240Y50365D01*
Y48045D01*
X244530Y46755D01*
X247126D01*
X247676Y46205D01*
Y45105D01*
X245388Y42817D01*
Y23920D01*
X244094Y22626D01*
Y13762D01*
G01X263778Y73426D02*
X263777D01*
X262450Y72099D01*
Y70923D01*
X264593Y68780D01*
Y63923D01*
X261580Y60910D01*
X255930D01*
X252433Y57413D01*
Y41910D01*
X262250Y32093D01*
Y24155D01*
X263779Y22626D01*
Y13762D01*
G01X259843Y65551D02*
X259842D01*
Y68319D01*
X260673Y69150D01*
X262313D01*
X263243Y68220D01*
Y64483D01*
X261020Y62260D01*
X255370D01*
X251083Y57973D01*
Y41350D01*
X260900Y31533D01*
Y24010D01*
X259842Y22952D01*
Y13762D01*
G01X279528Y73426D02*
X279527D01*
X278243Y72142D01*
Y70910D01*
X280403Y68750D01*
Y62400D01*
X278233Y60230D01*
Y38937D01*
X278763Y38407D01*
X283740D01*
X285080Y37067D01*
Y34847D01*
X283740Y33507D01*
X278763D01*
X278233Y32977D01*
Y23920D01*
X279527Y22626D01*
Y13762D01*
G01X275593Y65551D02*
X275592D01*
Y67809D01*
X276873Y69090D01*
X278153D01*
X279053Y68190D01*
Y62960D01*
X276883Y60790D01*
Y38377D01*
X278203Y37057D01*
X283180D01*
X283730Y36507D01*
Y35407D01*
X283180Y34857D01*
X278203D01*
X276883Y33537D01*
Y23920D01*
X275590Y22627D01*
Y13762D01*
G01X295278Y73426D02*
X295277D01*
Y71106D01*
X296533Y69850D01*
X301963D01*
X303583Y68230D01*
Y39450D01*
X301063Y36930D01*
X294833D01*
X292133Y34230D01*
Y29410D01*
X293982Y27561D01*
Y23920D01*
X295275Y22627D01*
Y13762D01*
G54D11*
X45633Y31600D03*
X38133Y31500D03*
X35363Y37960D03*
X108333Y31600D03*
X100733Y31500D03*
X92533D03*
X84233Y31400D03*
X77233Y31700D03*
X68633Y31400D03*
X60633Y31500D03*
X52733Y31400D03*
X163733Y31500D03*
X155433Y31600D03*
X147833Y31500D03*
X139733D03*
X132333Y31600D03*
X124233D03*
X116233Y31500D03*
X226933D03*
X219033Y31600D03*
X210633Y31500D03*
X202433Y31400D03*
X194933Y31600D03*
X188976Y31543D03*
X179133Y31600D03*
X171333D03*
X288533Y31020D03*
X280933Y31400D03*
X274433D03*
X266033Y31020D03*
X258233Y31300D03*
X249533Y31400D03*
X242333Y31600D03*
X234333Y31400D03*
X329633Y31100D03*
X338583Y32050D03*
X295275Y31658D03*
G54D21*
G01X181103Y65551D02*
Y65550D01*
X182396Y64257D01*
Y23920D01*
X181102Y22626D01*
Y13762D01*
G01X318898Y73426D02*
X318897D01*
Y64164D01*
X320436Y62625D01*
X326308D01*
X329233Y59700D01*
Y39700D01*
X318898Y29365D01*
Y13762D01*
G01X311023Y73426D02*
X311022D01*
X308953Y71357D01*
Y62620D01*
X305633Y59300D01*
Y41000D01*
X312733Y33900D01*
Y24700D01*
X311024Y22991D01*
Y13762D01*
G01X322833Y65551D02*
X324882D01*
X330233Y60200D01*
Y38800D01*
X322835Y31402D01*
Y13762D01*
G01X314963Y65551D02*
Y65550D01*
X318813Y61700D01*
X325733D01*
X328233Y59200D01*
Y40400D01*
X314961Y27128D01*
Y13762D01*
G01X334646D02*
Y25804D01*
X333090Y27360D01*
Y63320D01*
X333720Y63950D01*
Y72498D01*
X334648Y73426D01*
G01X326772Y13762D02*
Y33639D01*
X331233Y38100D01*
Y60800D01*
X326772Y65261D01*
Y73426D01*
X326773D01*
G01X350394Y15712D02*
Y29994D01*
X350396Y29996D01*
Y35224D01*
X348650Y36970D01*
Y62760D01*
X350393Y64503D01*
Y73426D01*
G01X330709Y13762D02*
Y25719D01*
X332158Y27168D01*
Y64100D01*
X330708Y65550D01*
Y65551D01*
G54D12*
X30680Y42700D03*
X23720Y37880D03*
X30833Y58700D03*
X21533Y59100D03*
X17033Y53450D03*
X15633Y69500D03*
X25733Y53450D03*
X15333Y62700D03*
X343019Y32504D03*
X347544Y32400D03*
X344360Y43670D03*
X343700Y53890D03*
X340080Y47960D03*
X340010Y58570D03*
X354650Y89890D03*
X355770Y78680D03*
X357350Y72160D03*
G54D13*
X16538Y78346D03*
X8950Y97440D03*
X8750Y50860D03*
X-2462Y651994D03*
X304528Y78346D03*
X364570Y96910D03*
X758452Y17317D03*
X755722Y677788D03*
G54D14*
X47243Y65551D03*
X43308Y73426D03*
X39373Y65551D03*
X35433Y73426D03*
X31498Y65551D03*
X27558Y73426D03*
X23623Y65551D03*
X47243Y91141D03*
X43308Y83266D03*
X39373Y91141D03*
X35433Y83266D03*
X31498Y91141D03*
X27558Y83266D03*
X23623Y91141D03*
X110238Y65551D03*
X106298Y73426D03*
X102363Y65551D03*
X98428Y73426D03*
X94488Y65551D03*
X90553Y73426D03*
X86613Y65551D03*
X82678Y73426D03*
X78743Y65551D03*
X74803Y73426D03*
X70868Y65551D03*
X66928Y73426D03*
X62993Y65551D03*
X59058Y73426D03*
X55118Y65551D03*
X51183Y73426D03*
X110238Y91141D03*
X106298Y83266D03*
X102363Y91141D03*
X98428Y83266D03*
X94488Y91141D03*
X90553Y83266D03*
X86613Y91141D03*
X82678Y83266D03*
X78743Y91141D03*
X74803Y83266D03*
X70868Y91141D03*
X66928Y83266D03*
X62993Y91141D03*
X59058Y83266D03*
X55118Y91141D03*
X51183Y83266D03*
X169293Y73426D03*
X165353Y65551D03*
X161418Y73426D03*
X157483Y65551D03*
X153543Y73426D03*
X149608Y65551D03*
X145668Y73426D03*
X141733Y65551D03*
X137798Y73426D03*
X133858Y65551D03*
X129923Y73426D03*
X125983Y65551D03*
X122048Y73426D03*
X118113Y65551D03*
X114173Y73426D03*
X169293Y83266D03*
X165353Y91141D03*
X161418Y83266D03*
X157483Y91141D03*
X153543Y83266D03*
X149608Y91141D03*
X145668Y83266D03*
X141733Y91141D03*
X137798Y83266D03*
X133858Y91141D03*
X129923Y83266D03*
X125983Y91141D03*
X122048Y83266D03*
X118113Y91141D03*
X114173Y83266D03*
X232283Y73426D03*
X228348Y65551D03*
X224408Y73426D03*
X220473Y65551D03*
X216538Y73426D03*
X212598Y65551D03*
X208663Y73426D03*
X204723Y65551D03*
X200788Y73426D03*
X196853Y65551D03*
X192913Y73426D03*
X188978Y65551D03*
X185038Y73426D03*
X181103Y65551D03*
X177168Y73426D03*
X173228Y65551D03*
X232283Y83266D03*
X228348Y91141D03*
X224408Y83266D03*
X220473Y91141D03*
X216538Y83266D03*
X212598Y91141D03*
X208663Y83266D03*
X204723Y91141D03*
X200788Y83266D03*
X196853Y91141D03*
X192913Y83266D03*
X188978Y91141D03*
X185038Y83266D03*
X181103Y91141D03*
X177168Y83266D03*
X173228Y91141D03*
X291338Y65551D03*
X287403Y73426D03*
X283463Y65551D03*
X279528Y73426D03*
X275593Y65551D03*
X271653Y73426D03*
X267718Y65551D03*
X263778Y73426D03*
X259843Y65551D03*
X255908Y73426D03*
X251968Y65551D03*
X248033Y73426D03*
X244093Y65551D03*
X240158Y73426D03*
X236223Y65551D03*
X291338Y91141D03*
X287403Y83266D03*
X283463Y91141D03*
X279528Y83266D03*
X275593Y91141D03*
X271653Y83266D03*
X267718Y91141D03*
X263778Y83266D03*
X259843Y91141D03*
X255908Y83266D03*
X251968Y91141D03*
X248033Y83266D03*
X244093Y91141D03*
X240158Y83266D03*
X236223Y91141D03*
X350393Y73426D03*
X346458Y65551D03*
X342518Y73426D03*
X338583Y65551D03*
X334648Y73426D03*
X330708Y65551D03*
X326773Y73426D03*
X322833Y65551D03*
X318898Y73426D03*
X314963Y65551D03*
X311023Y73426D03*
X299213Y65551D03*
X295278Y73426D03*
X350393Y83266D03*
X346458Y91141D03*
X342518Y83266D03*
X338583Y91141D03*
X334648Y83266D03*
X330708Y91141D03*
X326773Y83266D03*
X322833Y91141D03*
X318898Y83266D03*
X314963Y91141D03*
X311023Y83266D03*
X299213Y91141D03*
X295278Y83266D03*
G54D15*
X350394Y15712D03*
G54D16*
G01X-67189Y-77263D02*
G02I-12000J0D01*
G01X-72339D02*
G02I-6850J0D01*
G01X-79189Y-93263D02*
Y-61263D01*
G01X-63189Y-77263D02*
X-95189D01*
G01X-63189Y-93263D02*
Y-173263D01*
G01D02*
X1156611D01*
G01X-63189Y-93263D02*
X1156611D01*
G01X-63189Y-128763D02*
X1156611D01*
G01X47244Y13762D02*
Y29989D01*
X45633Y31600D01*
G01X35433Y25260D02*
X35273Y25420D01*
X32733D01*
X31496Y24183D01*
Y13762D01*
G01X35433Y25260D02*
Y13762D01*
G01X38133Y31500D02*
X35433Y28800D01*
Y25260D01*
G01X23623Y61999D02*
Y65551D01*
G01D02*
Y69103D01*
G01X20071Y65551D02*
X23623D01*
G01D02*
X27175D01*
G01X27558Y69874D02*
Y73426D01*
G01D02*
Y76978D01*
G01X24006Y73426D02*
X27558D01*
G01D02*
X31110D01*
G01X110236Y13762D02*
Y29697D01*
X108333Y31600D01*
G01X98425Y13762D02*
Y29192D01*
X100733Y31500D01*
G01X94488Y13762D02*
Y29545D01*
X92533Y31500D01*
G01X82677Y13762D02*
Y29844D01*
X84233Y31400D01*
G01X78740Y13762D02*
Y30193D01*
X77233Y31700D01*
G01X66929Y13762D02*
Y29696D01*
X68633Y31400D01*
G01X62992Y13762D02*
Y29141D01*
X60633Y31500D01*
G01X51181Y13762D02*
Y29848D01*
X52733Y31400D01*
G01X161417Y13762D02*
Y29184D01*
X163733Y31500D01*
G01X157480Y13762D02*
Y29553D01*
X155433Y31600D01*
G01X145669Y13762D02*
Y29336D01*
X147833Y31500D01*
G01X141732Y13762D02*
Y29501D01*
X139733Y31500D01*
G01X129921Y13762D02*
Y29188D01*
X132333Y31600D01*
G01X125984Y13762D02*
Y29849D01*
X124233Y31600D01*
G01X114173Y13762D02*
Y29440D01*
X116233Y31500D01*
G01X224409Y13762D02*
Y28976D01*
X226933Y31500D01*
G01X220472Y13762D02*
Y30161D01*
X219033Y31600D01*
G01X208661Y13762D02*
Y29528D01*
X210633Y31500D01*
G01X204724Y13762D02*
Y29109D01*
X202433Y31400D01*
G01X192913Y13762D02*
Y29580D01*
X194933Y31600D01*
G01X188976Y13762D02*
Y31543D01*
G01X177165Y13762D02*
Y29632D01*
X179133Y31600D01*
G01X173228Y13762D02*
Y29705D01*
X171333Y31600D01*
G01X283464Y13762D02*
Y28869D01*
X280933Y31400D01*
G01X271653Y13762D02*
Y28620D01*
X274433Y31400D01*
G01X255905Y13762D02*
Y28972D01*
X258233Y31300D01*
G01X251968Y13762D02*
Y28965D01*
X249533Y31400D01*
G01X240157Y13762D02*
Y29424D01*
X242333Y31600D01*
G01X236220Y13762D02*
Y29513D01*
X234333Y31400D01*
G01X287401Y13762D02*
Y29888D01*
X288533Y31020D01*
G01X267716Y13762D02*
Y29337D01*
X266033Y31020D01*
G01X338583Y13762D02*
Y32050D01*
G01X299212Y13762D02*
Y27721D01*
X295275Y31658D01*
G01X342518Y79714D02*
Y83266D01*
G01D02*
Y86818D01*
G01X338966Y83266D02*
X342518D01*
G01D02*
X346070D01*
G01X346458Y87589D02*
Y91141D01*
G01D02*
Y94693D01*
G01X342906Y91141D02*
X346458D01*
G01D02*
X350010D01*
G01X350393Y79714D02*
Y83266D01*
G01D02*
Y86818D01*
G01X346841Y83266D02*
X350393D01*
G01D02*
X353945D01*
G01X342518Y69874D02*
Y73426D01*
G01D02*
Y76978D01*
G01X338966Y73426D02*
X342518D01*
G01D02*
X346070D01*
G01X346458Y65551D02*
Y69103D01*
G01X342906Y65551D02*
X346458D01*
G01X369111Y-93263D02*
Y-173263D01*
G01X506611Y-93263D02*
Y-173263D01*
G01X621611Y-93263D02*
Y-173263D01*
G01X789111Y-93263D02*
Y-173263D01*
G01X959111Y-93263D02*
Y-173263D01*
G01X1156611Y-93263D02*
Y-173263D01*
G01X1184611Y-77263D02*
G02I-12000J0D01*
G01X1179461D02*
G02I-6850J0D01*
G01X1172611Y-93263D02*
Y-61263D01*
G01X1188611Y-77263D02*
X1156611D01*
G54D17*
G01X27559Y13762D02*
Y27474D01*
G01X23622Y26789D02*
Y13762D01*
G01X346457Y24224D02*
Y13762D01*
G01X342520D02*
Y25913D01*
G54D18*
G01X200788Y73426D02*
X200787D01*
Y64254D01*
X199333Y62800D01*
Y28600D01*
X200787Y27146D01*
Y13762D01*
G01X196853Y65551D02*
Y65550D01*
X198033Y64370D01*
Y28200D01*
X196850Y27017D01*
Y13762D01*
G01X185038Y73426D02*
X185037D01*
Y58289D01*
X183746Y56998D01*
Y23920D01*
X185039Y22627D01*
Y13762D01*
G54D19*
G01X-44374Y-163263D02*
Y-145763D01*
G01X-35204D02*
Y-163263D01*
G01Y-154513D02*
X-44374D01*
G01X-22289Y-163263D02*
X-23599Y-162971D01*
X-24909Y-161805D01*
X-25783Y-159763D01*
X-26219Y-157430D01*
X-25783Y-155096D01*
X-24909Y-153055D01*
X-23599Y-151888D01*
X-22289Y-151597D01*
X-20979Y-151888D01*
X-19669Y-153055D01*
X-18796Y-155096D01*
X-18577Y-157430D01*
X-18796Y-159763D01*
X-19669Y-161805D01*
X-20979Y-162971D01*
X-22289Y-163263D01*
G01X-8501D02*
Y-151597D01*
G01Y-154513D02*
X-7627Y-153055D01*
X-6317Y-151888D01*
X-4571Y-151597D01*
X-3043Y-151888D01*
X-1732Y-153055D01*
X-1077Y-155096D01*
Y-163263D01*
G01X9436Y-155388D02*
X16423D01*
X15768Y-153346D01*
X14676Y-152180D01*
X13148Y-151597D01*
X11619Y-151888D01*
X10309Y-152763D01*
X9436Y-154805D01*
X8999Y-156555D01*
Y-158305D01*
X9436Y-160055D01*
X10528Y-161805D01*
X11838Y-162971D01*
X13366Y-163263D01*
X14894Y-162680D01*
X16423Y-160930D01*
G01X25626Y-168513D02*
X26936Y-169096D01*
X28683Y-168513D01*
X29774Y-167347D01*
X30648Y-165888D01*
X31957Y-161222D01*
X34796Y-151597D01*
G01X27809D02*
X31957Y-161222D01*
G01X66957Y-153930D02*
X67831Y-153055D01*
X68486Y-151597D01*
X68923Y-149554D01*
X68486Y-147805D01*
X67613Y-146638D01*
X66084Y-145763D01*
X60189D01*
Y-163263D01*
X67394D01*
X68923Y-162097D01*
X69796Y-160346D01*
X70233Y-158305D01*
X69796Y-156263D01*
X68486Y-154513D01*
X66957Y-153930D01*
X60189D01*
G01X86641Y-163263D02*
Y-151597D01*
G01Y-153638D02*
X85768Y-152472D01*
X84457Y-151888D01*
X82929Y-151597D01*
X81401Y-152180D01*
X80091Y-153346D01*
X79217Y-155096D01*
X78781Y-157430D01*
X79217Y-159763D01*
X80091Y-161513D01*
X81401Y-162680D01*
X82929Y-163263D01*
X84457Y-162971D01*
X85768Y-162097D01*
X86641Y-160930D01*
G01X104141Y-145763D02*
Y-163263D01*
G01Y-160639D02*
X103268Y-162097D01*
X101957Y-162971D01*
X100429Y-163263D01*
X98683Y-162680D01*
X97373Y-161222D01*
X96499Y-159472D01*
X96281Y-157430D01*
X96499Y-155388D01*
X97373Y-153638D01*
X98683Y-152180D01*
X100429Y-151597D01*
X101957Y-151888D01*
X103049Y-152472D01*
X104141Y-153638D01*
G01X114654Y-167638D02*
X116183Y-168805D01*
X117929Y-169096D01*
X119457Y-168805D01*
X120768Y-167347D01*
X121641Y-165305D01*
Y-151597D01*
G01Y-153930D02*
X120768Y-152763D01*
X119457Y-151888D01*
X117929Y-151597D01*
X116183Y-152180D01*
X115091Y-153346D01*
X114217Y-155388D01*
X113781Y-157430D01*
X113999Y-159180D01*
X114873Y-161222D01*
X116183Y-162680D01*
X117929Y-163263D01*
X119239Y-162971D01*
X120768Y-161805D01*
X121641Y-160639D01*
G01X131936Y-155388D02*
X138923D01*
X138268Y-153346D01*
X137176Y-152180D01*
X135648Y-151597D01*
X134119Y-151888D01*
X132809Y-152763D01*
X131936Y-154805D01*
X131499Y-156555D01*
Y-158305D01*
X131936Y-160055D01*
X133028Y-161805D01*
X134338Y-162971D01*
X135866Y-163263D01*
X137394Y-162680D01*
X138923Y-160930D01*
G01X149654Y-163263D02*
Y-151597D01*
G01Y-153930D02*
X150746Y-152763D01*
X151838Y-151888D01*
X153366Y-151597D01*
X154457Y-151888D01*
X155768Y-152763D01*
G01X183344Y-163263D02*
Y-145763D01*
X188803D01*
X190549Y-146638D01*
X191641Y-147805D01*
X192078Y-150138D01*
X191641Y-152472D01*
X190331Y-153930D01*
X188803Y-154805D01*
X183344D01*
G01X188803D02*
X192078Y-163263D01*
G01X205211Y-151597D02*
Y-163263D01*
G01Y-146930D02*
X204774Y-146638D01*
Y-146055D01*
X205211Y-145763D01*
X205648Y-146055D01*
Y-146638D01*
X205211Y-146930D01*
G01X219436Y-161222D02*
X220528Y-162388D01*
X222056Y-163263D01*
X223366D01*
X224676Y-162680D01*
X225549Y-161805D01*
X225986Y-160639D01*
X225768Y-158888D01*
X224894Y-158013D01*
X220964Y-156263D01*
X220091Y-154221D01*
X220528Y-152763D01*
X221401Y-151888D01*
X222711Y-151597D01*
X224021Y-151888D01*
X225331Y-152763D01*
G01X236936Y-155388D02*
X243923D01*
X243268Y-153346D01*
X242176Y-152180D01*
X240648Y-151597D01*
X239119Y-151888D01*
X237809Y-152763D01*
X236936Y-154805D01*
X236499Y-156555D01*
Y-158305D01*
X236936Y-160055D01*
X238028Y-161805D01*
X239338Y-162971D01*
X240866Y-163263D01*
X242394Y-162680D01*
X243923Y-160930D01*
G01X254654Y-163263D02*
Y-151597D01*
G01Y-153930D02*
X255746Y-152763D01*
X256838Y-151888D01*
X258366Y-151597D01*
X259457Y-151888D01*
X260768Y-152763D01*
G01X297514Y-147222D02*
X296204Y-146346D01*
X294676Y-145763D01*
X292929D01*
X290964Y-146638D01*
X289436Y-148096D01*
X288344Y-149847D01*
X287471Y-152763D01*
X287252Y-155388D01*
X287689Y-158013D01*
X288344Y-159763D01*
X289654Y-161513D01*
X291183Y-162680D01*
X292711Y-163263D01*
X294239D01*
X295768Y-162680D01*
X297078Y-161805D01*
X298170Y-160639D01*
G01X314141Y-163263D02*
Y-151597D01*
G01Y-153638D02*
X313268Y-152472D01*
X311957Y-151888D01*
X310429Y-151597D01*
X308901Y-152180D01*
X307591Y-153346D01*
X306717Y-155096D01*
X306281Y-157430D01*
X306717Y-159763D01*
X307591Y-161513D01*
X308901Y-162680D01*
X310429Y-163263D01*
X311957Y-162971D01*
X313268Y-162097D01*
X314141Y-160930D01*
G01X324654Y-163263D02*
Y-151597D01*
G01Y-153930D02*
X325746Y-152763D01*
X326838Y-151888D01*
X328366Y-151597D01*
X329457Y-151888D01*
X330768Y-152763D01*
G01X349141Y-145763D02*
Y-163263D01*
G01Y-160639D02*
X348268Y-162097D01*
X346957Y-162971D01*
X345429Y-163263D01*
X343683Y-162680D01*
X342373Y-161222D01*
X341499Y-159472D01*
X341281Y-157430D01*
X341499Y-155388D01*
X342373Y-153638D01*
X343683Y-152180D01*
X345429Y-151597D01*
X346957Y-151888D01*
X348049Y-152472D01*
X349141Y-153638D01*
G01X112034Y-118263D02*
Y-100763D01*
X117711Y-115346D01*
X123388Y-100763D01*
Y-118263D01*
G01X135211D02*
X133901Y-117971D01*
X132591Y-116805D01*
X131717Y-114763D01*
X131281Y-112430D01*
X131717Y-110096D01*
X132591Y-108055D01*
X133901Y-106888D01*
X135211Y-106597D01*
X136521Y-106888D01*
X137831Y-108055D01*
X138704Y-110096D01*
X138923Y-112430D01*
X138704Y-114763D01*
X137831Y-116805D01*
X136521Y-117971D01*
X135211Y-118263D01*
G01X156641Y-100763D02*
Y-118263D01*
G01Y-115639D02*
X155768Y-117097D01*
X154457Y-117971D01*
X152929Y-118263D01*
X151183Y-117680D01*
X149873Y-116222D01*
X148999Y-114472D01*
X148781Y-112430D01*
X148999Y-110388D01*
X149873Y-108638D01*
X151183Y-107180D01*
X152929Y-106597D01*
X154457Y-106888D01*
X155549Y-107472D01*
X156641Y-108638D01*
G01X166936Y-110388D02*
X173923D01*
X173268Y-108346D01*
X172176Y-107180D01*
X170648Y-106597D01*
X169119Y-106888D01*
X167809Y-107763D01*
X166936Y-109805D01*
X166499Y-111555D01*
Y-113305D01*
X166936Y-115055D01*
X168028Y-116805D01*
X169338Y-117971D01*
X170866Y-118263D01*
X172394Y-117680D01*
X173923Y-115930D01*
G01X187711Y-118263D02*
Y-100763D01*
G01X402811Y-163263D02*
Y-145763D01*
X400191Y-149263D01*
G01Y-163263D02*
X405431D01*
G01X415508Y-159763D02*
X416817Y-161805D01*
X418564Y-162971D01*
X420529Y-163263D01*
X422276Y-162971D01*
X424023Y-161513D01*
X425114Y-159763D01*
X425333Y-158013D01*
X424896Y-155972D01*
X423368Y-154513D01*
X421839Y-153930D01*
X419874D01*
G01X421839D02*
X423149Y-153055D01*
X424241Y-151597D01*
X424678Y-149847D01*
X424241Y-148096D01*
X423149Y-146638D01*
X421184Y-145763D01*
X419219Y-146055D01*
X417254Y-147222D01*
G01X434099Y-161222D02*
X435628Y-162680D01*
X437374Y-163263D01*
X439121Y-162680D01*
X440649Y-160930D01*
X441741Y-158305D01*
X442178Y-155680D01*
Y-152472D01*
X441741Y-149847D01*
X440649Y-147513D01*
X439339Y-146346D01*
X437811Y-145763D01*
X436064Y-146346D01*
X434754Y-147513D01*
X433881Y-149263D01*
X433444Y-151597D01*
X433881Y-153638D01*
X434973Y-155680D01*
X436283Y-156847D01*
X437811Y-157138D01*
X439557Y-156555D01*
X440868Y-155096D01*
X442178Y-152472D01*
G01X455311Y-163263D02*
Y-145763D01*
X452691Y-149263D01*
G01Y-163263D02*
X457931D01*
G01X469099Y-161222D02*
X470628Y-162680D01*
X472374Y-163263D01*
X474121Y-162680D01*
X475649Y-160930D01*
X476741Y-158305D01*
X477178Y-155680D01*
Y-152472D01*
X476741Y-149847D01*
X475649Y-147513D01*
X474339Y-146346D01*
X472811Y-145763D01*
X471064Y-146346D01*
X469754Y-147513D01*
X468881Y-149263D01*
X468444Y-151597D01*
X468881Y-153638D01*
X469973Y-155680D01*
X471283Y-156847D01*
X472811Y-157138D01*
X474557Y-156555D01*
X475868Y-155096D01*
X477178Y-152472D01*
G01X389694Y-118263D02*
Y-100763D01*
X394934D01*
X396681Y-101638D01*
X397991Y-103680D01*
X398428Y-106013D01*
X397991Y-108346D01*
X396899Y-110096D01*
X394934Y-110972D01*
X389694D01*
G01X416364Y-102222D02*
X415054Y-101346D01*
X413526Y-100763D01*
X411779D01*
X409814Y-101638D01*
X408286Y-103096D01*
X407194Y-104847D01*
X406321Y-107763D01*
X406102Y-110388D01*
X406539Y-113013D01*
X407194Y-114763D01*
X408504Y-116513D01*
X410033Y-117680D01*
X411561Y-118263D01*
X413089D01*
X414618Y-117680D01*
X415928Y-116805D01*
X417020Y-115639D01*
G01X430807Y-108930D02*
X431681Y-108055D01*
X432336Y-106597D01*
X432773Y-104554D01*
X432336Y-102805D01*
X431463Y-101638D01*
X429934Y-100763D01*
X424039D01*
Y-118263D01*
X431244D01*
X432773Y-117097D01*
X433646Y-115346D01*
X434083Y-113305D01*
X433646Y-111263D01*
X432336Y-109513D01*
X430807Y-108930D01*
X424039D01*
G01X440011Y-124096D02*
X453111D01*
G01X459039Y-118263D02*
Y-100763D01*
X469083Y-118263D01*
Y-100763D01*
G01X481561Y-118263D02*
X479814Y-117971D01*
X478286Y-116805D01*
X476976Y-115055D01*
X476102Y-113013D01*
X475666Y-110680D01*
Y-108346D01*
X476102Y-106013D01*
X476976Y-103971D01*
X478286Y-102222D01*
X479814Y-101055D01*
X481561Y-100763D01*
X483307Y-101055D01*
X484836Y-102222D01*
X486146Y-103971D01*
X487020Y-106013D01*
X487456Y-108346D01*
Y-110680D01*
X487020Y-113013D01*
X486146Y-115055D01*
X484836Y-116805D01*
X483307Y-117971D01*
X481561Y-118263D01*
G01X532402Y-100763D02*
X537861Y-118263D01*
X543320Y-100763D01*
G01X559728Y-118263D02*
X550994D01*
Y-100763D01*
X559728D01*
G01X556234Y-109221D02*
X550994D01*
G01X568494Y-118263D02*
Y-100763D01*
X573953D01*
X575699Y-101638D01*
X576791Y-102805D01*
X577228Y-105138D01*
X576791Y-107472D01*
X575481Y-108930D01*
X573953Y-109805D01*
X568494D01*
G01X573953D02*
X577228Y-118263D01*
G01X590361Y-118846D02*
X589924Y-118555D01*
Y-117971D01*
X590361Y-117680D01*
X590798Y-117971D01*
Y-118555D01*
X590361Y-118846D01*
G01X550776Y-160930D02*
X552523Y-162388D01*
X554488Y-163263D01*
X556234D01*
X557981Y-162388D01*
X559291Y-160930D01*
X559946Y-158888D01*
X559509Y-156847D01*
X558418Y-155096D01*
X556453Y-153930D01*
X553833Y-153346D01*
X552304Y-152180D01*
X551649Y-150138D01*
X552086Y-148096D01*
X553178Y-146638D01*
X554706Y-145763D01*
X556234D01*
X557763Y-146346D01*
X559073Y-147805D01*
G01X567402Y-163263D02*
X572861Y-145763D01*
X578320Y-163263D01*
G01X576354Y-157138D02*
X569367D01*
G01X692194Y-145763D02*
Y-163263D01*
X700928D01*
G01X714061D02*
Y-145763D01*
X711441Y-149263D01*
G01Y-163263D02*
X716681D01*
G01X665944Y-100763D02*
Y-118263D01*
X674678D01*
G01X691741D02*
Y-106597D01*
G01Y-108638D02*
X690868Y-107472D01*
X689557Y-106888D01*
X688029Y-106597D01*
X686501Y-107180D01*
X685191Y-108346D01*
X684317Y-110096D01*
X683881Y-112430D01*
X684317Y-114763D01*
X685191Y-116513D01*
X686501Y-117680D01*
X688029Y-118263D01*
X689557Y-117971D01*
X690868Y-117097D01*
X691741Y-115930D01*
G01X700726Y-123513D02*
X702036Y-124096D01*
X703783Y-123513D01*
X704874Y-122347D01*
X705748Y-120888D01*
X707057Y-116222D01*
X709896Y-106597D01*
G01X702909D02*
X707057Y-116222D01*
G01X719536Y-110388D02*
X726523D01*
X725868Y-108346D01*
X724776Y-107180D01*
X723248Y-106597D01*
X721719Y-106888D01*
X720409Y-107763D01*
X719536Y-109805D01*
X719099Y-111555D01*
Y-113305D01*
X719536Y-115055D01*
X720628Y-116805D01*
X721938Y-117971D01*
X723466Y-118263D01*
X724994Y-117680D01*
X726523Y-115930D01*
G01X737254Y-118263D02*
Y-106597D01*
G01Y-108930D02*
X738346Y-107763D01*
X739438Y-106888D01*
X740966Y-106597D01*
X742057Y-106888D01*
X743368Y-107763D01*
G01X808058Y-118263D02*
Y-100763D01*
X812424D01*
X814171Y-101638D01*
X815481Y-102805D01*
X816573Y-104554D01*
X817446Y-106597D01*
X817664Y-109513D01*
X817446Y-112430D01*
X816573Y-114472D01*
X815481Y-116222D01*
X814171Y-117388D01*
X812424Y-118263D01*
X808058D01*
G01X827086Y-110388D02*
X834073D01*
X833418Y-108346D01*
X832326Y-107180D01*
X830798Y-106597D01*
X829269Y-106888D01*
X827959Y-107763D01*
X827086Y-109805D01*
X826649Y-111555D01*
Y-113305D01*
X827086Y-115055D01*
X828178Y-116805D01*
X829488Y-117971D01*
X831016Y-118263D01*
X832544Y-117680D01*
X834073Y-115930D01*
G01X844586Y-116222D02*
X845678Y-117388D01*
X847206Y-118263D01*
X848516D01*
X849826Y-117680D01*
X850699Y-116805D01*
X851136Y-115639D01*
X850918Y-113888D01*
X850044Y-113013D01*
X846114Y-111263D01*
X845241Y-109221D01*
X845678Y-107763D01*
X846551Y-106888D01*
X847861Y-106597D01*
X849171Y-106888D01*
X850481Y-107763D01*
G01X865361Y-106597D02*
Y-118263D01*
G01Y-101930D02*
X864924Y-101638D01*
Y-101055D01*
X865361Y-100763D01*
X865798Y-101055D01*
Y-101638D01*
X865361Y-101930D01*
G01X879804Y-122638D02*
X881333Y-123805D01*
X883079Y-124096D01*
X884607Y-123805D01*
X885918Y-122347D01*
X886791Y-120305D01*
Y-106597D01*
G01Y-108930D02*
X885918Y-107763D01*
X884607Y-106888D01*
X883079Y-106597D01*
X881333Y-107180D01*
X880241Y-108346D01*
X879367Y-110388D01*
X878931Y-112430D01*
X879149Y-114180D01*
X880023Y-116222D01*
X881333Y-117680D01*
X883079Y-118263D01*
X884389Y-117971D01*
X885918Y-116805D01*
X886791Y-115639D01*
G01X896649Y-118263D02*
Y-106597D01*
G01Y-109513D02*
X897523Y-108055D01*
X898833Y-106888D01*
X900579Y-106597D01*
X902107Y-106888D01*
X903418Y-108055D01*
X904073Y-110096D01*
Y-118263D01*
G01X914586Y-110388D02*
X921573D01*
X920918Y-108346D01*
X919826Y-107180D01*
X918298Y-106597D01*
X916769Y-106888D01*
X915459Y-107763D01*
X914586Y-109805D01*
X914149Y-111555D01*
Y-113305D01*
X914586Y-115055D01*
X915678Y-116805D01*
X916988Y-117971D01*
X918516Y-118263D01*
X920044Y-117680D01*
X921573Y-115930D01*
G01X932304Y-118263D02*
Y-106597D01*
G01Y-108930D02*
X933396Y-107763D01*
X934488Y-106888D01*
X936016Y-106597D01*
X937107Y-106888D01*
X938418Y-107763D01*
G01X853991Y-145763D02*
X859231D01*
G01X856611D02*
Y-163263D01*
G01X853991D02*
X859231D01*
G01X868652Y-145763D02*
X874111Y-163263D01*
X879570Y-145763D01*
G01X891611Y-163263D02*
Y-155388D01*
X887244Y-145763D01*
G01X895978D02*
X891611Y-155388D01*
G01X979061Y-163263D02*
Y-145763D01*
X976441Y-149263D01*
G01Y-163263D02*
X981681D01*
G01X996561D02*
Y-145763D01*
X993941Y-149263D01*
G01Y-163263D02*
X999181D01*
G01X1010131Y-163846D02*
X1017991Y-145763D01*
G01X1027413Y-148680D02*
X1028723Y-146930D01*
X1030251Y-146055D01*
X1031998Y-145763D01*
X1034181Y-146346D01*
X1035709Y-147805D01*
X1036146Y-149554D01*
X1035928Y-151305D01*
X1035054Y-152763D01*
X1030688Y-155680D01*
X1028723Y-157721D01*
X1027413Y-160639D01*
X1026976Y-163263D01*
X1036146D01*
G01X1044913Y-148680D02*
X1046223Y-146930D01*
X1047751Y-146055D01*
X1049498Y-145763D01*
X1051681Y-146346D01*
X1053209Y-147805D01*
X1053646Y-149554D01*
X1053428Y-151305D01*
X1052554Y-152763D01*
X1048188Y-155680D01*
X1046223Y-157721D01*
X1044913Y-160639D01*
X1044476Y-163263D01*
X1053646D01*
G01X1062631Y-163846D02*
X1070491Y-145763D01*
G01X1079913Y-148680D02*
X1081223Y-146930D01*
X1082751Y-146055D01*
X1084498Y-145763D01*
X1086681Y-146346D01*
X1088209Y-147805D01*
X1088646Y-149554D01*
X1088428Y-151305D01*
X1087554Y-152763D01*
X1083188Y-155680D01*
X1081223Y-157721D01*
X1079913Y-160639D01*
X1079476Y-163263D01*
X1088646D01*
G01X1101561Y-145763D02*
X1099814Y-146346D01*
X1098504Y-147805D01*
X1097631Y-149554D01*
X1096976Y-151888D01*
X1096758Y-154513D01*
X1096976Y-157138D01*
X1097631Y-159472D01*
X1098504Y-161222D01*
X1099814Y-162680D01*
X1101561Y-163263D01*
X1103307Y-162680D01*
X1104618Y-161222D01*
X1105491Y-159472D01*
X1106146Y-157138D01*
X1106364Y-154513D01*
X1106146Y-151888D01*
X1105491Y-149554D01*
X1104618Y-147805D01*
X1103307Y-146346D01*
X1101561Y-145763D01*
G01X1119061Y-163263D02*
Y-145763D01*
X1116441Y-149263D01*
G01Y-163263D02*
X1121681D01*
G01X1131758Y-159763D02*
X1133067Y-161805D01*
X1134814Y-162971D01*
X1136779Y-163263D01*
X1138526Y-162971D01*
X1140273Y-161513D01*
X1141364Y-159763D01*
X1141583Y-158013D01*
X1141146Y-155972D01*
X1139618Y-154513D01*
X1138089Y-153930D01*
X1136124D01*
G01X1138089D02*
X1139399Y-153055D01*
X1140491Y-151597D01*
X1140928Y-149847D01*
X1140491Y-148096D01*
X1139399Y-146638D01*
X1137434Y-145763D01*
X1135469Y-146055D01*
X1133504Y-147222D01*
G01X1026758Y-118263D02*
Y-100763D01*
X1031124D01*
X1032871Y-101638D01*
X1034181Y-102805D01*
X1035273Y-104554D01*
X1036146Y-106597D01*
X1036364Y-109513D01*
X1036146Y-112430D01*
X1035273Y-114472D01*
X1034181Y-116222D01*
X1032871Y-117388D01*
X1031124Y-118263D01*
X1026758D01*
G01X1052991D02*
Y-106597D01*
G01Y-108638D02*
X1052118Y-107472D01*
X1050807Y-106888D01*
X1049279Y-106597D01*
X1047751Y-107180D01*
X1046441Y-108346D01*
X1045567Y-110096D01*
X1045131Y-112430D01*
X1045567Y-114763D01*
X1046441Y-116513D01*
X1047751Y-117680D01*
X1049279Y-118263D01*
X1050807Y-117971D01*
X1052118Y-117097D01*
X1052991Y-115930D01*
G01X1066561Y-100763D02*
Y-118263D01*
G01X1063504Y-106597D02*
X1069618D01*
G01X1080786Y-110388D02*
X1087773D01*
X1087118Y-108346D01*
X1086026Y-107180D01*
X1084498Y-106597D01*
X1082969Y-106888D01*
X1081659Y-107763D01*
X1080786Y-109805D01*
X1080349Y-111555D01*
Y-113305D01*
X1080786Y-115055D01*
X1081878Y-116805D01*
X1083188Y-117971D01*
X1084716Y-118263D01*
X1086244Y-117680D01*
X1087773Y-115930D01*
M02*
